(kicad_pcb
	(version 20260206)
	(generator "pcbnew")
	(generator_version "10.0")
	(general
		(thickness 1.6)
		(legacy_teardrops no)
	)
	(paper "A4")
	(title_block
		(title "pdpb — Lightning_PDPB_BRD.brd")
		(comment 1 "Lightning (Wiwynn / Facebook NVMe JBOF) / footprints 866-870 of 1140")
	)
	(layers
		(0 "F.Cu" signal "TOP")
		(4 "In1.Cu" signal "L2GND")
		(6 "In2.Cu" signal "L3")
		(8 "In3.Cu" signal "L4VCC")
		(10 "In4.Cu" signal "L5VCC")
		(12 "In5.Cu" signal "L6")
		(14 "In6.Cu" signal "L7GND")
		(2 "B.Cu" signal "BOTTOM")
		(9 "F.Adhes" user "F.Adhesive")
		(11 "B.Adhes" user "B.Adhesive")
		(13 "F.Paste" user "Package Geometry/Pastemask Top")
		(15 "B.Paste" user "Package Geometry/Pastemask Bottom")
		(5 "F.SilkS" user "Ref Des/Silkscreen Top")
		(7 "B.SilkS" user "Ref Des/Silkscreen Bottom")
		(1 "F.Mask" user "Board Geometry/Soldermask Top")
		(3 "B.Mask" user "Board Geometry/Soldermask Bottom")
		(17 "Dwgs.User" user "User.Drawings")
		(19 "Cmts.User" user "User.Comments")
		(21 "Eco1.User" user "User.Eco1")
		(23 "Eco2.User" user "User.Eco2")
		(25 "Edge.Cuts" user "Board Geometry/Outline")
		(27 "Margin" user)
		(31 "F.CrtYd" user "Package Geometry/Place Bound Top")
		(29 "B.CrtYd" user "Package Geometry/Place Bound Bottom")
		(35 "F.Fab" user "Ref Des/Assembly Top")
		(33 "B.Fab" user "Ref Des/Assembly Bottom")
	)
	(footprint ""
		(layer "F.Cu")
		(at 24.253698 -463.78241 -90)
		(property "Reference" "R115"
			(at 0 0 270)
			(layer "F.SilkS")
			(hide yes)
			(effects
				(font
					(size 1.27 1.27)
				)
			)
		)
		(property "Value" "100R2J-2-GP"
			(at 0.064008 -3.993896 270)
			(unlocked yes)
			(layer "F.Fab")
			(hide yes)
			(effects
				(font
					(size 1.016 1.016)
					(thickness 0.1524)
				)
			)
		)
		(property "Device Type" "R402H14"
			(at 0.064008 -5.517896 270)
			(unlocked yes)
			(layer "F.Fab")
			(hide yes)
			(effects
				(font
					(size 1.016 1.016)
					(thickness 0.1524)
				)
			)
		)
		(duplicate_pad_numbers_are_jumpers no)
		(fp_line
			(start -0.508 -0.9398)
			(end -0.508 0.9398)
			(stroke
				(width 0.1524)
				(type default)
			)
			(layer "F.SilkS")
		)
		(fp_line
			(start 0.508 -0.9398)
			(end -0.508 -0.9398)
			(stroke
				(width 0.1524)
				(type default)
			)
			(layer "F.SilkS")
		)
		(fp_rect
			(start -0.508 0.9398)
			(end 0.508 -0.9398)
			(stroke
				(width 0)
				(type default)
			)
			(fill no)
			(layer "F.CrtYd")
		)
		(fp_rect
			(start -0.508 0.9398)
			(end 0.508 -0.9398)
			(stroke
				(width 0)
				(type default)
			)
			(fill no)
			(layer "F.Fab")
		)
		(pad "1" smd custom
			(at 0 -0.4445 270)
			(size 0.1397 0.1397)
			(layers "F.Cu" "F.Mask" "F.Paste")
			(net "P3V3")
			(options
				(clearance outline)
				(anchor circle)
			)
			(primitives
				(gr_poly
					(pts
						(arc
							(start -0.1778 -0.2794)
							(mid -0.249642 -0.249642)
							(end -0.2794 -0.1778)
						)
						(arc
							(start -0.2794 0.1778)
							(mid -0.249642 0.249642)
							(end -0.1778 0.2794)
						)
						(arc
							(start 0.1778 0.2794)
							(mid 0.249642 0.249642)
							(end 0.2794 0.1778)
						)
						(arc
							(start 0.2794 -0.1778)
							(mid 0.249642 -0.249642)
							(end 0.1778 -0.2794)
						)
					)
					(width 0)
					(fill yes)
				)
			)
		)
		(pad "2" smd custom
			(at 0 0.4445 270)
			(size 0.1397 0.1397)
			(layers "F.Cu" "F.Mask" "F.Paste")
			(net "DRV_ACT_10")
			(options
				(clearance outline)
				(anchor circle)
			)
			(primitives
				(gr_poly
					(pts
						(arc
							(start -0.1778 -0.2794)
							(mid -0.249642 -0.249642)
							(end -0.2794 -0.1778)
						)
						(arc
							(start -0.2794 0.1778)
							(mid -0.249642 0.249642)
							(end -0.1778 0.2794)
						)
						(arc
							(start 0.1778 0.2794)
							(mid 0.249642 0.249642)
							(end 0.2794 0.1778)
						)
						(arc
							(start 0.2794 -0.1778)
							(mid 0.249642 -0.249642)
							(end 0.1778 -0.2794)
						)
					)
					(width 0)
					(fill yes)
				)
			)
		)
	)
	(footprint ""
		(layer "F.Cu")
		(at 86.614 -211.963 180)
		(property "Reference" "C8916"
			(at 0 0 180)
			(layer "F.SilkS")
			(hide yes)
			(effects
				(font
					(size 1.27 1.27)
				)
			)
		)
		(property "Value" "SC1U10V2KX-7-GP"
			(at 1.1811 -2.7051 180)
			(unlocked yes)
			(layer "F.Fab")
			(hide yes)
			(effects
				(font
					(size 1.016 1.016)
					(thickness 0.1524)
				)
			)
		)
		(property "Device Type" "C402H22"
			(at 1.1811 -4.2291 180)
			(unlocked yes)
			(layer "F.Fab")
			(hide yes)
			(effects
				(font
					(size 1.016 1.016)
					(thickness 0.1524)
				)
			)
		)
		(duplicate_pad_numbers_are_jumpers no)
		(fp_rect
			(start -0.4318 0.9525)
			(end 0.4318 -0.9525)
			(stroke
				(width 0)
				(type default)
			)
			(fill no)
			(layer "F.CrtYd")
		)
		(fp_rect
			(start -0.4318 0.9525)
			(end 0.4318 -0.9525)
			(stroke
				(width 0)
				(type default)
			)
			(fill no)
			(layer "F.Fab")
		)
		(pad "1" smd custom
			(at 0 -0.4445 180)
			(size 0.1524 0.1524)
			(layers "F.Cu" "F.Mask" "F.Paste")
			(net "VDDR_3")
			(options
				(clearance outline)
				(anchor circle)
			)
			(primitives
				(gr_poly
					(pts
						(arc
							(start 0.3048 -0.2032)
							(mid 0.275042 -0.275042)
							(end 0.2032 -0.3048)
						)
						(arc
							(start -0.2032 -0.3048)
							(mid -0.275042 -0.275042)
							(end -0.3048 -0.2032)
						)
						(arc
							(start -0.3048 0.2032)
							(mid -0.275042 0.275042)
							(end -0.2032 0.3048)
						)
						(arc
							(start 0.2032 0.3048)
							(mid 0.275042 0.275042)
							(end 0.3048 0.2032)
						)
					)
					(width 0)
					(fill yes)
				)
			)
		)
		(pad "2" smd custom
			(at 0 0.4445 180)
			(size 0.1524 0.1524)
			(layers "F.Cu" "F.Mask" "F.Paste")
			(net "GND")
			(options
				(clearance outline)
				(anchor circle)
			)
			(primitives
				(gr_poly
					(pts
						(arc
							(start 0.3048 -0.2032)
							(mid 0.275042 -0.275042)
							(end 0.2032 -0.3048)
						)
						(arc
							(start -0.2032 -0.3048)
							(mid -0.275042 -0.275042)
							(end -0.3048 -0.2032)
						)
						(arc
							(start -0.3048 0.2032)
							(mid -0.275042 0.275042)
							(end -0.2032 0.3048)
						)
						(arc
							(start 0.2032 0.3048)
							(mid 0.275042 0.275042)
							(end 0.3048 0.2032)
						)
					)
					(width 0)
					(fill yes)
				)
			)
		)
	)
	(footprint ""
		(layer "F.Cu")
		(at 58.293 -241.675158 180)
		(property "Reference" "SR1135"
			(at 0 0 180)
			(layer "F.SilkS")
			(hide yes)
			(effects
				(font
					(size 1.27 1.27)
				)
			)
		)
		(property "Value" "4K7R2F-GP"
			(at 0.064008 -3.993896 180)
			(unlocked yes)
			(layer "F.Fab")
			(hide yes)
			(effects
				(font
					(size 1.016 1.016)
					(thickness 0.1524)
				)
			)
		)
		(property "Device Type" "R402H16"
			(at 0.064008 -5.517896 180)
			(unlocked yes)
			(layer "F.Fab")
			(hide yes)
			(effects
				(font
					(size 1.016 1.016)
					(thickness 0.1524)
				)
			)
		)
		(duplicate_pad_numbers_are_jumpers no)
		(fp_line
			(start 0.508 -0.9398)
			(end -0.508 -0.9398)
			(stroke
				(width 0.1524)
				(type default)
			)
			(layer "F.SilkS")
		)
		(fp_line
			(start -0.508 -0.9398)
			(end -0.508 0.9398)
			(stroke
				(width 0.1524)
				(type default)
			)
			(layer "F.SilkS")
		)
		(fp_rect
			(start -0.508 0.9398)
			(end 0.508 -0.9398)
			(stroke
				(width 0)
				(type default)
			)
			(fill no)
			(layer "F.CrtYd")
		)
		(fp_rect
			(start -0.508 0.9398)
			(end 0.508 -0.9398)
			(stroke
				(width 0)
				(type default)
			)
			(fill no)
			(layer "F.Fab")
		)
		(pad "1" smd custom
			(at 0 -0.4445 180)
			(size 0.1397 0.1397)
			(layers "F.Cu" "F.Mask" "F.Paste")
			(net "P3V3")
			(options
				(clearance outline)
				(anchor circle)
			)
			(primitives
				(gr_poly
					(pts
						(arc
							(start -0.1778 -0.2794)
							(mid -0.249642 -0.249642)
							(end -0.2794 -0.1778)
						)
						(arc
							(start -0.2794 0.1778)
							(mid -0.249642 0.249642)
							(end -0.1778 0.2794)
						)
						(arc
							(start 0.1778 0.2794)
							(mid 0.249642 0.249642)
							(end 0.2794 0.1778)
						)
						(arc
							(start 0.2794 -0.1778)
							(mid 0.249642 -0.249642)
							(end 0.1778 -0.2794)
						)
					)
					(width 0)
					(fill yes)
				)
			)
		)
		(pad "2" smd custom
			(at 0 0.4445 180)
			(size 0.1397 0.1397)
			(layers "F.Cu" "F.Mask" "F.Paste")
			(net "SSD7_CLK0_OE_MOS_N")
			(options
				(clearance outline)
				(anchor circle)
			)
			(primitives
				(gr_poly
					(pts
						(arc
							(start -0.1778 -0.2794)
							(mid -0.249642 -0.249642)
							(end -0.2794 -0.1778)
						)
						(arc
							(start -0.2794 0.1778)
							(mid -0.249642 0.249642)
							(end -0.1778 0.2794)
						)
						(arc
							(start 0.1778 0.2794)
							(mid 0.249642 0.249642)
							(end 0.2794 0.1778)
						)
						(arc
							(start 0.2794 -0.1778)
							(mid 0.249642 -0.249642)
							(end 0.1778 -0.2794)
						)
					)
					(width 0)
					(fill yes)
				)
			)
		)
	)
	(footprint ""
		(layer "F.Cu")
		(at 246.253 -425.831)
		(property "Reference" "TP2"
			(at 0 0 0)
			(layer "F.SilkS")
			(hide yes)
			(effects
				(font
					(size 1.27 1.27)
				)
			)
		)
		(property "Value" "TPAD28-2-GP"
			(at -0.0127 -1.6637 0)
			(unlocked yes)
			(layer "F.Fab")
			(hide yes)
			(effects
				(font
					(size 1.016 1.016)
					(thickness 0.1524)
				)
			)
		)
		(property "Device Type" "TPAD28"
			(at -0.0127 -3.1877 0)
			(unlocked yes)
			(layer "F.Fab")
			(hide yes)
			(effects
				(font
					(size 1.016 1.016)
					(thickness 0.1524)
				)
			)
		)
		(duplicate_pad_numbers_are_jumpers no)
		(fp_poly
			(pts
				(arc
					(start 0.3556 0)
					(mid -0.3556 0)
					(end 0.3556 0)
				)
			)
			(stroke
				(width 0)
				(type default)
			)
			(fill no)
			(layer "F.CrtYd")
		)
		(fp_poly
			(pts
				(arc
					(start 0.6096 0)
					(mid -0.6096 0)
					(end 0.6096 0)
				)
			)
			(stroke
				(width 0)
				(type default)
			)
			(fill no)
			(layer "F.Fab")
		)
		(pad "1" smd circle
			(at 0 0)
			(size 0.7112 0.7112)
			(layers "F.Cu" "F.Mask" "F.Paste")
			(net "N70930468")
		)
	)
	(footprint ""
		(layer "F.Cu")
		(at 78.5622 -305.6255)
		(property "Reference" "R9963"
			(at 0 0 0)
			(layer "F.SilkS")
			(hide yes)
			(effects
				(font
					(size 1.27 1.27)
				)
			)
		)
		(property "Value" "470R2F-GP"
			(at 0.064008 -3.993896 0)
			(unlocked yes)
			(layer "F.Fab")
			(hide yes)
			(effects
				(font
					(size 1.016 1.016)
					(thickness 0.1524)
				)
			)
		)
		(property "Device Type" "R402H16"
			(at 0.064008 -5.517896 0)
			(unlocked yes)
			(layer "F.Fab")
			(hide yes)
			(effects
				(font
					(size 1.016 1.016)
					(thickness 0.1524)
				)
			)
		)
		(duplicate_pad_numbers_are_jumpers no)
		(fp_line
			(start -0.508 -0.9398)
			(end -0.508 0.9398)
			(stroke
				(width 0.1524)
				(type default)
			)
			(layer "F.SilkS")
		)
		(fp_line
			(start 0.508 -0.9398)
			(end -0.508 -0.9398)
			(stroke
				(width 0.1524)
				(type default)
			)
			(layer "F.SilkS")
		)
		(fp_rect
			(start -0.508 0.9398)
			(end 0.508 -0.9398)
			(stroke
				(width 0)
				(type default)
			)
			(fill no)
			(layer "F.CrtYd")
		)
		(fp_rect
			(start -0.508 0.9398)
			(end 0.508 -0.9398)
			(stroke
				(width 0)
				(type default)
			)
			(fill no)
			(layer "F.Fab")
		)
		(pad "1" smd custom
			(at 0 -0.4445)
			(size 0.1397 0.1397)
			(layers "F.Cu" "F.Mask" "F.Paste")
			(net "VDD_DIFF_2")
			(options
				(clearance outline)
				(anchor circle)
			)
			(primitives
				(gr_poly
					(pts
						(arc
							(start -0.1778 -0.2794)
							(mid -0.249642 -0.249642)
							(end -0.2794 -0.1778)
						)
						(arc
							(start -0.2794 0.1778)
							(mid -0.249642 0.249642)
							(end -0.1778 0.2794)
						)
						(arc
							(start 0.1778 0.2794)
							(mid 0.249642 0.249642)
							(end 0.2794 0.1778)
						)
						(arc
							(start 0.2794 -0.1778)
							(mid 0.249642 -0.249642)
							(end 0.1778 -0.2794)
						)
					)
					(width 0)
					(fill yes)
				)
			)
		)
		(pad "2" smd custom
			(at 0 0.4445)
			(size 0.1397 0.1397)
			(layers "F.Cu" "F.Mask" "F.Paste")
			(net "PE_100M_CLK3_P")
			(options
				(clearance outline)
				(anchor circle)
			)
			(primitives
				(gr_poly
					(pts
						(arc
							(start -0.1778 -0.2794)
							(mid -0.249642 -0.249642)
							(end -0.2794 -0.1778)
						)
						(arc
							(start -0.2794 0.1778)
							(mid -0.249642 0.249642)
							(end -0.1778 0.2794)
						)
						(arc
							(start 0.1778 0.2794)
							(mid 0.249642 0.249642)
							(end 0.2794 0.1778)
						)
						(arc
							(start 0.2794 -0.1778)
							(mid 0.249642 -0.249642)
							(end 0.1778 -0.2794)
						)
					)
					(width 0)
					(fill yes)
				)
			)
		)
	)
)
